# T6G (Grand Teton) — schematic netlist excerpt (pin names and nets, part order shuffled) for the footprints in the layout excerpt that follows; sources: Cadence DE-HDL packaged netlist, KiCad conversion of 04192023_DAF0TMB3IC0_F0TG_MB_C_brd_V02_OCP.brd

PR194  Q_RES  2.2 1% CHIP  pkg 0402LF  page 212 : A = PVDDCR_CPU0_P1_PVCC ; B = PVDDCR_CPU0_P1_VCC4
C2285  Q_CAP  22UF 4V 20% X6S  pkg C0402  page 72 : A = PVDD11_S3_P1 ; B = GND

(kicad_pcb
	(version 20260206)
	(generator "pcbnew")
	(generator_version "10.0")
	(general
		(thickness 1.6)
		(legacy_teardrops no)
	)
	(paper "A4")
	(title_block
		(title "04192023_DAF0TMB3IC0_F0TG_MB_C_brd_V02_OCP.brd")
		(comment 1 "Grand Teton / footprints 5968-5969 of 8354")
	)
	(layers
		(0 "F.Cu" signal "TOP")
		(4 "In1.Cu" signal "GND")
		(6 "In2.Cu" signal "IN1")
		(8 "In3.Cu" signal "GND1")
		(10 "In4.Cu" signal "IN2")
		(12 "In5.Cu" signal "GND2")
		(14 "In6.Cu" signal "IN3")
		(16 "In7.Cu" signal "GND3")
		(18 "In8.Cu" signal "VCC")
		(20 "In9.Cu" signal "VCC1")
		(22 "In10.Cu" signal "GND4")
		(24 "In11.Cu" signal "IN4")
		(26 "In12.Cu" signal "GND5")
		(28 "In13.Cu" signal "IN5")
		(30 "In14.Cu" signal "GND6")
		(32 "In15.Cu" signal "IN6")
		(34 "In16.Cu" signal "GND7")
		(2 "B.Cu" signal "BOTTOM")
		(9 "F.Adhes" user "F.Adhesive")
		(11 "B.Adhes" user "B.Adhesive")
		(13 "F.Paste" user "Package Geometry/Pastemask Top")
		(15 "B.Paste" user "Package Geometry/Pastemask Bottom")
		(5 "F.SilkS" user "Ref Des/Silkscreen Top")
		(7 "B.SilkS" user "Ref Des/Silkscreen Bottom")
		(1 "F.Mask" user "Board Geometry/Soldermask Top")
		(3 "B.Mask" user "Board Geometry/Soldermask Bottom")
		(17 "Dwgs.User" user "User.Drawings")
		(19 "Cmts.User" user "User.Comments")
		(21 "Eco1.User" user "User.Eco1")
		(23 "Eco2.User" user "User.Eco2")
		(25 "Edge.Cuts" user "Board Geometry/Outline")
		(27 "Margin" user)
		(31 "F.CrtYd" user "Package Geometry/Place Bound Top")
		(29 "B.CrtYd" user "Package Geometry/Place Bound Bottom")
		(35 "F.Fab" user "Ref Des/Assembly Top")
		(33 "B.Fab" user "Ref Des/Assembly Bottom")
	)
	(footprint ""
		(layer "B.Cu")
		(at 110.149386 -266.005564)
		(property "Reference" "C2285"
			(at 0 0 0)
			(layer "B.SilkS")
			(hide yes)
			(effects
				(font
					(size 1.27 1.27)
				)
				(justify mirror)
			)
		)
		(property "Value" ""
			(at 0 0 0)
			(layer "B.Fab")
			(effects
				(font
					(size 1.27 1.27)
				)
				(justify mirror)
			)
		)
		(duplicate_pad_numbers_are_jumpers no)
		(fp_line
			(start -0.7874 -0.4064)
			(end -0.7874 0.4064)
			(stroke
				(width 0.1524)
				(type default)
			)
			(layer "B.SilkS")
		)
		(fp_line
			(start -0.7874 0.4064)
			(end 0.7874 0.4064)
			(stroke
				(width 0.1524)
				(type default)
			)
			(layer "B.SilkS")
		)
		(fp_line
			(start 0.7874 -0.4064)
			(end -0.7874 -0.4064)
			(stroke
				(width 0.1524)
				(type default)
			)
			(layer "B.SilkS")
		)
		(fp_line
			(start 0.7874 0.4064)
			(end 0.7874 -0.4064)
			(stroke
				(width 0.1524)
				(type default)
			)
			(layer "B.SilkS")
		)
		(fp_line
			(start -0.67945 -0.3048)
			(end -0.67945 0.3048)
			(stroke
				(width 0.1)
				(type default)
			)
			(layer "B.Fab")
		)
		(fp_line
			(start -0.67945 0.3048)
			(end -0.120396 0.3048)
			(stroke
				(width 0.1)
				(type default)
			)
			(layer "B.Fab")
		)
		(fp_line
			(start -0.12065 -0.3048)
			(end -0.67945 -0.3048)
			(stroke
				(width 0.1)
				(type default)
			)
			(layer "B.Fab")
		)
		(fp_line
			(start -0.12065 -0.2794)
			(end -0.12065 -0.3048)
			(stroke
				(width 0.1)
				(type default)
			)
			(layer "B.Fab")
		)
		(fp_line
			(start -0.120396 0.2794)
			(end 0.12065 0.2794)
			(stroke
				(width 0.1)
				(type default)
			)
			(layer "B.Fab")
		)
		(fp_line
			(start -0.120396 0.3048)
			(end -0.120396 0.2794)
			(stroke
				(width 0.1)
				(type default)
			)
			(layer "B.Fab")
		)
		(fp_line
			(start 0.12065 -0.305054)
			(end 0.12065 -0.2794)
			(stroke
				(width 0.1)
				(type default)
			)
			(layer "B.Fab")
		)
		(fp_line
			(start 0.12065 -0.2794)
			(end -0.12065 -0.2794)
			(stroke
				(width 0.1)
				(type default)
			)
			(layer "B.Fab")
		)
		(fp_line
			(start 0.12065 0.2794)
			(end 0.12065 0.3048)
			(stroke
				(width 0.1)
				(type default)
			)
			(layer "B.Fab")
		)
		(fp_line
			(start 0.12065 0.3048)
			(end 0.67945 0.3048)
			(stroke
				(width 0.1)
				(type default)
			)
			(layer "B.Fab")
		)
		(fp_line
			(start 0.67945 -0.305054)
			(end 0.12065 -0.305054)
			(stroke
				(width 0.1)
				(type default)
			)
			(layer "B.Fab")
		)
		(fp_line
			(start 0.67945 0.3048)
			(end 0.67945 -0.305054)
			(stroke
				(width 0.1)
				(type default)
			)
			(layer "B.Fab")
		)
		(pad "1" smd circle
			(at 0.40005 0 180)
			(size 0 0)
			(layers "B.Cu" "B.Mask" "B.Paste")
			(net "PVDD11_S3_P1")
		)
		(pad "2" smd circle
			(at -0.40005 0 180)
			(size 0 0)
			(layers "B.Cu" "B.Mask" "B.Paste")
			(net "GND")
		)
	)
	(footprint ""
		(layer "B.Cu")
		(at 109.766862 -177.112676 90)
		(property "Reference" "PR194"
			(at 0 0 90)
			(layer "B.SilkS")
			(hide yes)
			(effects
				(font
					(size 1.27 1.27)
				)
				(justify mirror)
			)
		)
		(property "Value" ""
			(at 0 0 90)
			(layer "B.Fab")
			(effects
				(font
					(size 1.27 1.27)
				)
				(justify mirror)
			)
		)
		(duplicate_pad_numbers_are_jumpers no)
		(fp_line
			(start 0.7874 -0.4064)
			(end -0.7874 -0.4064)
			(stroke
				(width 0.1524)
				(type default)
			)
			(layer "B.SilkS")
		)
		(fp_line
			(start -0.7874 -0.4064)
			(end -0.7874 0.4064)
			(stroke
				(width 0.1524)
				(type default)
			)
			(layer "B.SilkS")
		)
		(fp_line
			(start 0.7874 0.4064)
			(end 0.7874 -0.4064)
			(stroke
				(width 0.1524)
				(type default)
			)
			(layer "B.SilkS")
		)
		(fp_line
			(start -0.7874 0.4064)
			(end 0.7874 0.4064)
			(stroke
				(width 0.1524)
				(type default)
			)
			(layer "B.SilkS")
		)
		(fp_line
			(start 0.67945 -0.305054)
			(end 0.12065 -0.305054)
			(stroke
				(width 0.1)
				(type default)
			)
			(layer "B.Fab")
		)
		(fp_line
			(start 0.12065 -0.305054)
			(end 0.12065 -0.2794)
			(stroke
				(width 0.1)
				(type default)
			)
			(layer "B.Fab")
		)
		(fp_line
			(start -0.12065 -0.3048)
			(end -0.67945 -0.3048)
			(stroke
				(width 0.1)
				(type default)
			)
			(layer "B.Fab")
		)
		(fp_line
			(start -0.67945 -0.3048)
			(end -0.67945 0.3048)
			(stroke
				(width 0.1)
				(type default)
			)
			(layer "B.Fab")
		)
		(fp_line
			(start 0.12065 -0.2794)
			(end -0.12065 -0.2794)
			(stroke
				(width 0.1)
				(type default)
			)
			(layer "B.Fab")
		)
		(fp_line
			(start -0.12065 -0.2794)
			(end -0.12065 -0.3048)
			(stroke
				(width 0.1)
				(type default)
			)
			(layer "B.Fab")
		)
		(fp_line
			(start 0.12065 0.2794)
			(end 0.12065 0.3048)
			(stroke
				(width 0.1)
				(type default)
			)
			(layer "B.Fab")
		)
		(fp_line
			(start -0.120396 0.2794)
			(end 0.12065 0.2794)
			(stroke
				(width 0.1)
				(type default)
			)
			(layer "B.Fab")
		)
		(fp_line
			(start 0.67945 0.3048)
			(end 0.67945 -0.305054)
			(stroke
				(width 0.1)
				(type default)
			)
			(layer "B.Fab")
		)
		(fp_line
			(start 0.12065 0.3048)
			(end 0.67945 0.3048)
			(stroke
				(width 0.1)
				(type default)
			)
			(layer "B.Fab")
		)
		(fp_line
			(start -0.120396 0.3048)
			(end -0.120396 0.2794)
			(stroke
				(width 0.1)
				(type default)
			)
			(layer "B.Fab")
		)
		(fp_line
			(start -0.67945 0.3048)
			(end -0.120396 0.3048)
			(stroke
				(width 0.1)
				(type default)
			)
			(layer "B.Fab")
		)
		(pad "1" smd circle
			(at 0.40005 0 270)
			(size 0 0)
			(layers "B.Cu" "B.Mask" "B.Paste")
			(net "PVDDCR_CPU0_P1_PVCC")
		)
		(pad "2" smd circle
			(at -0.40005 0 270)
			(size 0 0)
			(layers "B.Cu" "B.Mask" "B.Paste")
			(net "PVDDCR_CPU0_P1_VCC4")
		)
	)
)
